(kicad_pcb
	(version 20241229)
	(generator "pcbnew")
	(generator_version "9.0")
	(general
		(thickness 1.62)
		(legacy_teardrops no)
	)
	(paper "A4")
	(title_block
		(title "OCuLink to 10GbE adapter")
		(date "2026-02-23")
		(rev "1.1.0")
		(company "Antmicro Ltd")
		(comment 1 "www.antmicro.com")
		(comment 9 "footprint 265 of 510 (U9), pads 324-400 of 503")
	)
	(layers
		(0 "F.Cu" signal)
		(4 "In1.Cu" signal)
		(6 "In2.Cu" signal)
		(8 "In3.Cu" signal)
		(10 "In4.Cu" signal)
		(12 "In5.Cu" signal)
		(14 "In6.Cu" signal)
		(2 "B.Cu" signal)
		(9 "F.Adhes" user "F.Adhesive")
		(11 "B.Adhes" user "B.Adhesive")
		(13 "F.Paste" user)
		(15 "B.Paste" user)
		(5 "F.SilkS" user "F.Silkscreen")
		(7 "B.SilkS" user "B.Silkscreen")
		(1 "F.Mask" user)
		(3 "B.Mask" user)
		(17 "Dwgs.User" user "User.Drawings")
		(19 "Cmts.User" user "User.Comments")
		(21 "Eco1.User" user "User.Eco1")
		(23 "Eco2.User" user "User.Eco2")
		(25 "Edge.Cuts" user)
		(27 "Margin" user)
		(31 "F.CrtYd" user "F.Courtyard")
		(29 "B.CrtYd" user "B.Courtyard")
		(35 "F.Fab" user)
		(33 "B.Fab" user)
	)
	(footprint "antmicro-footprints:FCBGA-503_22x22mm_Layout21x24_P1mm"
		(locked yes)
		(layer "F.Cu")
		(at 84.975 100 180)
		(property "Reference" "U9"
			(at -11.275 11.4 0)
			(layer "F.SilkS")
			(effects
				(font
					(size 0.7 0.7)
					(thickness 0.15)
				)
				(justify right bottom)
			)
		)
		(property "Value" "EZX710AT2_S_LMR5"
			(at -11.4 12.5 0)
			(layer "F.Fab")
			(hide yes)
			(effects
				(font
					(size 0.7 0.7)
					(thickness 0.15)
				)
				(justify right top)
			)
		)
		(property "Datasheet" "https://www.google.com/url?sa=t&source=web&rct=j&opi=89978449&url=https://cdrdv2-public.intel.com/596333/596333_X710-TM4_Datasheet_v_2_4.pdf&ved=2ahUKEwiSuv20_sCOAxXVCRAIHdxGO_UQFnoECBEQAQ&usg=AOvVaw1CjGyrGWE8ZvOdw4VBsY6U"
			(at -16.625 -13.91 0)
			(layer "F.Fab")
			(hide yes)
			(effects
				(font
					(size 0.7 0.7)
					(thickness 0.15)
				)
				(justify right top)
			)
		)
		(property "Description" "Ethernet ICs Intel Ethernet Controller 10 Gigabit X7"
			(at -12.015 -0.89 0)
			(layer "F.Fab")
			(hide yes)
			(effects
				(font
					(size 0.7 0.7)
					(thickness 0.15)
				)
				(justify right top)
			)
		)
		(property "MPN" "EZX710AT2 S LMR5"
			(at 0 0 180)
			(unlocked yes)
			(layer "F.Fab")
			(hide yes)
			(effects
				(font
					(size 1 1)
					(thickness 0.15)
				)
			)
		)
		(property "Manufacturer" "Intel"
			(at 0 0 180)
			(unlocked yes)
			(layer "F.Fab")
			(hide yes)
			(effects
				(font
					(size 1 1)
					(thickness 0.15)
				)
			)
		)
		(property "Author" "Antmicro"
			(at 0 0 180)
			(unlocked yes)
			(layer "F.Fab")
			(hide yes)
			(effects
				(font
					(size 1 1)
					(thickness 0.15)
				)
			)
		)
		(property "License" "Apache-2.0"
			(at 0 0 180)
			(unlocked yes)
			(layer "F.Fab")
			(hide yes)
			(effects
				(font
					(size 1 1)
					(thickness 0.15)
				)
			)
		)
		(sheetname "/X710-AT2 power/")
		(sheetfile "x710-at2-power.kicad_sch")
		(attr smd)
		(pad "M20" smd circle
			(at -0.75 -0.435 180)
			(size 0.5 0.5)
			(layers "F.Cu" "F.Mask" "F.Paste")
			(net 28 "GND")
			(pinfunction "VSS")
			(pintype "passive")
		)
		(pad "M22" smd circle
			(at 0.25 -0.435 180)
			(size 0.5 0.5)
			(layers "F.Cu" "F.Mask" "F.Paste")
			(net 264 "unconnected-(U9E-RSVDM22_NC-PadM22)")
			(pinfunction "RSVDM22_NC")
			(pintype "passive+no_connect")
		)
		(pad "M24" smd circle
			(at 1.25 -0.435 180)
			(size 0.5 0.5)
			(layers "F.Cu" "F.Mask" "F.Paste")
			(net 279 "unconnected-(U9E-RSVDM24_NC-PadM24)")
			(pinfunction "RSVDM24_NC")
			(pintype "passive+no_connect")
		)
		(pad "M26" smd circle
			(at 2.25 -0.435 180)
			(size 0.5 0.5)
			(layers "F.Cu" "F.Mask" "F.Paste")
			(net 229 "unconnected-(U9E-RSVDM26_NC-PadM26)")
			(pinfunction "RSVDM26_NC")
			(pintype "passive+no_connect")
		)
		(pad "M28" smd circle
			(at 3.25 -0.435 180)
			(size 0.5 0.5)
			(layers "F.Cu" "F.Mask" "F.Paste")
			(net 355 "unconnected-(U9E-RSVDM28_NC-PadM28)")
			(pinfunction "RSVDM28_NC")
			(pintype "passive+no_connect")
		)
		(pad "M30" smd circle
			(at 4.25 -0.435 180)
			(size 0.5 0.5)
			(layers "F.Cu" "F.Mask" "F.Paste")
			(net 268 "unconnected-(U9G-RSVDM30_NC-PadM30)")
			(pinfunction "RSVDM30_NC")
			(pintype "passive+no_connect")
		)
		(pad "M32" smd circle
			(at 5.25 -0.435 180)
			(size 0.5 0.5)
			(layers "F.Cu" "F.Mask" "F.Paste")
			(net 219 "unconnected-(U9G-RSVDM32_NC-PadM32)")
			(pinfunction "RSVDM32_NC")
			(pintype "passive+no_connect")
		)
		(pad "M34" smd circle
			(at 6.25 -0.435 180)
			(size 0.5 0.5)
			(layers "F.Cu" "F.Mask" "F.Paste")
			(net 208 "unconnected-(U9F-RSVDM34_NC-PadM34)")
			(pinfunction "RSVDM34_NC")
			(pintype "passive+no_connect")
		)
		(pad "M36" smd circle
			(at 7.25 -0.435 180)
			(size 0.5 0.5)
			(layers "F.Cu" "F.Mask" "F.Paste")
			(net 196 "unconnected-(U9F-RSVDM36_NC-PadM36)")
			(pinfunction "RSVDM36_NC")
			(pintype "passive+no_connect")
		)
		(pad "M38" smd circle
			(at 8.25 -0.435 180)
			(size 0.5 0.5)
			(layers "F.Cu" "F.Mask" "F.Paste")
			(net 18 "+1V88")
			(pinfunction "VDDP2")
			(pintype "power_in")
		)
		(pad "M40" smd circle
			(at 9.25 -0.435 180)
			(size 0.5 0.5)
			(layers "F.Cu" "F.Mask" "F.Paste")
			(net 142 "/X710-AT2 10GbE/~{P0_INT}")
			(pinfunction "P0_INT_MLC")
			(pintype "passive")
		)
		(pad "M42" smd circle
			(at 10.25 -0.435 180)
			(size 0.5 0.5)
			(layers "F.Cu" "F.Mask" "F.Paste")
			(net 381 "/X710-AT2 Misc/MDIO.MDIO")
			(pinfunction "MDIO")
			(pintype "bidirectional")
		)
		(pad "N1" smd circle
			(at -10.25 0.43 180)
			(size 0.5 0.5)
			(layers "F.Cu" "F.Mask" "F.Paste")
			(net 132 "/X710-AT2 10GbE/MDIO0_SDA0")
			(pinfunction "MDIO0_SDA0")
			(pintype "bidirectional")
		)
		(pad "N3" smd circle
			(at -9.25 0.43 180)
			(size 0.5 0.5)
			(layers "F.Cu" "F.Mask" "F.Paste")
			(net 130 "/X710-AT2 10GbE/MDC0_SCL0")
			(pinfunction "MDC0_SCL0")
			(pintype "output")
		)
		(pad "N5" smd circle
			(at -8.25 0.43 180)
			(size 0.5 0.5)
			(layers "F.Cu" "F.Mask" "F.Paste")
			(net 172 "unconnected-(U9C-SDP3_0-PadN5)")
			(pinfunction "SDP3_0")
			(pintype "passive+no_connect")
		)
		(pad "N7" smd circle
			(at -7.25 0.43 180)
			(size 0.5 0.5)
			(layers "F.Cu" "F.Mask" "F.Paste")
			(net 165 "unconnected-(U9C-SDP3_1-PadN7)")
			(pinfunction "SDP3_1")
			(pintype "passive+no_connect")
		)
		(pad "N9" smd circle
			(at -6.25 0.43 180)
			(size 0.5 0.5)
			(layers "F.Cu" "F.Mask" "F.Paste")
			(net 125 "/X710-AT2 RSVD/RSVDN9_VSS")
			(pinfunction "RSVDN9_VSS")
			(pintype "passive")
		)
		(pad "N11" smd circle
			(at -5.25 0.43 180)
			(size 0.5 0.5)
			(layers "F.Cu" "F.Mask" "F.Paste")
			(net 1 "VCCA")
			(pinfunction "VCCA")
			(pintype "passive")
		)
		(pad "N13" smd circle
			(at -4.25 0.43 180)
			(size 0.5 0.5)
			(layers "F.Cu" "F.Mask" "F.Paste")
			(net 1 "VCCA")
			(pinfunction "VCCA")
			(pintype "passive")
		)
		(pad "N15" smd circle
			(at -3.25 0.43 180)
			(size 0.5 0.5)
			(layers "F.Cu" "F.Mask" "F.Paste")
			(net 1 "VCCA")
			(pinfunction "VCCA")
			(pintype "passive")
		)
		(pad "N17" smd circle
			(at -2.25 0.43 180)
			(size 0.5 0.5)
			(layers "F.Cu" "F.Mask" "F.Paste")
			(net 9 "VCCD")
			(pinfunction "VCCD")
			(pintype "passive")
		)
		(pad "N19" smd circle
			(at -1.25 0.43 180)
			(size 0.5 0.5)
			(layers "F.Cu" "F.Mask" "F.Paste")
			(net 9 "VCCD")
			(pinfunction "VCCD")
			(pintype "passive")
		)
		(pad "N21" smd circle
			(at -0.25 0.43 180)
			(size 0.5 0.5)
			(layers "F.Cu" "F.Mask" "F.Paste")
			(net 9 "VCCD")
			(pinfunction "VCCD")
			(pintype "passive")
		)
		(pad "N23" smd circle
			(at 0.75 0.43 180)
			(size 0.5 0.5)
			(layers "F.Cu" "F.Mask" "F.Paste")
			(net 276 "unconnected-(U9E-RSVDN23_NC-PadN23)")
			(pinfunction "RSVDN23_NC")
			(pintype "passive+no_connect")
		)
		(pad "N25" smd circle
			(at 1.75 0.43 180)
			(size 0.5 0.5)
			(layers "F.Cu" "F.Mask" "F.Paste")
			(net 251 "unconnected-(U9E-RSVDN25_NC-PadN25)")
			(pinfunction "RSVDN25_NC")
			(pintype "passive+no_connect")
		)
		(pad "N27" smd circle
			(at 2.75 0.43 180)
			(size 0.5 0.5)
			(layers "F.Cu" "F.Mask" "F.Paste")
			(net 266 "unconnected-(U9E-RSVDN27_NC-PadN27)")
			(pinfunction "RSVDN27_NC")
			(pintype "passive+no_connect")
		)
		(pad "N29" smd circle
			(at 3.75 0.43 180)
			(size 0.5 0.5)
			(layers "F.Cu" "F.Mask" "F.Paste")
			(net 248 "unconnected-(U9G-RSVDN29_NC-PadN29)")
			(pinfunction "RSVDN29_NC")
			(pintype "passive+no_connect")
		)
		(pad "N31" smd circle
			(at 4.75 0.43 180)
			(size 0.5 0.5)
			(layers "F.Cu" "F.Mask" "F.Paste")
			(net 372 "unconnected-(U9G-RSVDN31_NC-PadN31)")
			(pinfunction "RSVDN31_NC")
			(pintype "passive+no_connect")
		)
		(pad "N33" smd circle
			(at 5.75 0.43 180)
			(size 0.5 0.5)
			(layers "F.Cu" "F.Mask" "F.Paste")
			(net 270 "unconnected-(U9F-RSVDN33_NC-PadN33)")
			(pinfunction "RSVDN33_NC")
			(pintype "passive+no_connect")
		)
		(pad "N35" smd circle
			(at 6.75 0.43 180)
			(size 0.5 0.5)
			(layers "F.Cu" "F.Mask" "F.Paste")
			(net 203 "unconnected-(U9F-RSVDN35_NC-PadN35)")
			(pinfunction "RSVDN35_NC")
			(pintype "passive+no_connect")
		)
		(pad "N37" smd circle
			(at 7.75 0.43 180)
			(size 0.5 0.5)
			(layers "F.Cu" "F.Mask" "F.Paste")
			(net 28 "GND")
			(pinfunction "RSVDN37_VSS")
			(pintype "passive")
		)
		(pad "N39" smd circle
			(at 8.75 0.43 180)
			(size 0.5 0.5)
			(layers "F.Cu" "F.Mask" "F.Paste")
			(net 166 "unconnected-(U9F-P0_PTP_SYNC0-PadN39)")
			(pinfunction "P0_PTP_SYNC0")
			(pintype "passive+no_connect")
		)
		(pad "N41" smd circle
			(at 9.75 0.43 180)
			(size 0.5 0.5)
			(layers "F.Cu" "F.Mask" "F.Paste")
			(net 182 "unconnected-(U9F-P0_PTP_SYNC1-PadN41)")
			(pinfunction "P0_PTP_SYNC1")
			(pintype "passive+no_connect")
		)
		(pad "P2" smd circle
			(at -9.75 1.295 180)
			(size 0.5 0.5)
			(layers "F.Cu" "F.Mask" "F.Paste")
			(net 309 "/OCuLink/~{PE_WAKE}")
			(pinfunction "~{PE_WAKE}")
			(pintype "open_collector")
		)
		(pad "P4" smd circle
			(at -8.75 1.295 180)
			(size 0.5 0.5)
			(layers "F.Cu" "F.Mask" "F.Paste")
			(net 354 "unconnected-(U9C-SDP1_1-PadP4)")
			(pinfunction "SDP1_1")
			(pintype "passive+no_connect")
		)
		(pad "P6" smd circle
			(at -7.75 1.295 180)
			(size 0.5 0.5)
			(layers "F.Cu" "F.Mask" "F.Paste")
			(net 225 "unconnected-(U9C-SDP1_2-PadP6)")
			(pinfunction "SDP1_2")
			(pintype "passive+no_connect")
		)
		(pad "P8" smd circle
			(at -6.75 1.295 180)
			(size 0.5 0.5)
			(layers "F.Cu" "F.Mask" "F.Paste")
			(net 129 "/X710-AT2 RSVD/RSVDP8_VSS")
			(pinfunction "RSVDP8_VSS")
			(pintype "passive")
		)
		(pad "P10" smd circle
			(at -5.75 1.295 180)
			(size 0.5 0.5)
			(layers "F.Cu" "F.Mask" "F.Paste")
			(net 28 "GND")
			(pinfunction "VSS")
			(pintype "passive")
		)
		(pad "P12" smd circle
			(at -4.75 1.295 180)
			(size 0.5 0.5)
			(layers "F.Cu" "F.Mask" "F.Paste")
			(net 28 "GND")
			(pinfunction "VSS")
			(pintype "passive")
		)
		(pad "P14" smd circle
			(at -3.75 1.295 180)
			(size 0.5 0.5)
			(layers "F.Cu" "F.Mask" "F.Paste")
			(net 28 "GND")
			(pinfunction "VSS")
			(pintype "passive")
		)
		(pad "P16" smd circle
			(at -2.75 1.295 180)
			(size 0.5 0.5)
			(layers "F.Cu" "F.Mask" "F.Paste")
			(net 28 "GND")
			(pinfunction "VSS")
			(pintype "passive")
		)
		(pad "P18" smd circle
			(at -1.75 1.295 180)
			(size 0.5 0.5)
			(layers "F.Cu" "F.Mask" "F.Paste")
			(net 28 "GND")
			(pinfunction "VSS")
			(pintype "passive")
		)
		(pad "P20" smd circle
			(at -0.75 1.295 180)
			(size 0.5 0.5)
			(layers "F.Cu" "F.Mask" "F.Paste")
			(net 28 "GND")
			(pinfunction "VSS")
			(pintype "passive")
		)
		(pad "P22" smd circle
			(at 0.25 1.295 180)
			(size 0.5 0.5)
			(layers "F.Cu" "F.Mask" "F.Paste")
			(net 127 "/X710-AT2 RSVD/RSVDP22_VSS")
			(pinfunction "RSVDP22_VSS")
			(pintype "passive")
		)
		(pad "P24" smd circle
			(at 1.25 1.295 180)
			(size 0.5 0.5)
			(layers "F.Cu" "F.Mask" "F.Paste")
			(net 339 "unconnected-(U9E-RSVDP24_NC-PadP24)")
			(pinfunction "RSVDP24_NC")
			(pintype "passive+no_connect")
		)
		(pad "P26" smd circle
			(at 2.25 1.295 180)
			(size 0.5 0.5)
			(layers "F.Cu" "F.Mask" "F.Paste")
			(net 216 "unconnected-(U9E-RSVDP26_NC-PadP26)")
			(pinfunction "RSVDP26_NC")
			(pintype "passive+no_connect")
		)
		(pad "P28" smd circle
			(at 3.25 1.295 180)
			(size 0.5 0.5)
			(layers "F.Cu" "F.Mask" "F.Paste")
			(net 370 "unconnected-(U9E-RSVDP28_NC-PadP28)")
			(pinfunction "RSVDP28_NC")
			(pintype "passive+no_connect")
		)
		(pad "P30" smd circle
			(at 4.25 1.295 180)
			(size 0.5 0.5)
			(layers "F.Cu" "F.Mask" "F.Paste")
			(net 228 "unconnected-(U9G-RSVDP30_NC-PadP30)")
			(pinfunction "RSVDP30_NC")
			(pintype "passive+no_connect")
		)
		(pad "P32" smd circle
			(at 5.25 1.295 180)
			(size 0.5 0.5)
			(layers "F.Cu" "F.Mask" "F.Paste")
			(net 262 "unconnected-(U9G-RSVDP32_NC-PadP32)")
			(pinfunction "RSVDP32_NC")
			(pintype "passive+no_connect")
		)
		(pad "P34" smd circle
			(at 6.25 1.295 180)
			(size 0.5 0.5)
			(layers "F.Cu" "F.Mask" "F.Paste")
			(net 284 "unconnected-(U9F-RSVDP34_NC-PadP34)")
			(pinfunction "RSVDP34_NC")
			(pintype "passive+no_connect")
		)
		(pad "P36" smd circle
			(at 7.25 1.295 180)
			(size 0.5 0.5)
			(layers "F.Cu" "F.Mask" "F.Paste")
			(net 237 "unconnected-(U9F-RSVDP36_NC-PadP36)")
			(pinfunction "RSVDP36_NC")
			(pintype "passive+no_connect")
		)
		(pad "P38" smd circle
			(at 8.25 1.295 180)
			(size 0.5 0.5)
			(layers "F.Cu" "F.Mask" "F.Paste")
			(net 28 "GND")
			(pinfunction "RSVDP38_VSS")
			(pintype "passive")
		)
		(pad "P40" smd circle
			(at 9.25 1.295 180)
			(size 0.5 0.5)
			(layers "F.Cu" "F.Mask" "F.Paste")
			(net 107 "/X710-AT2 Misc/FLSH_SCK")
			(pinfunction "FLSH_SCK")
			(pintype "tri_state")
		)
		(pad "P42" smd circle
			(at 10.25 1.295 180)
			(size 0.5 0.5)
			(layers "F.Cu" "F.Mask" "F.Paste")
			(net 139 "/Flash memory/FLASH.MOSI")
			(pinfunction "FLSH_SI")
			(pintype "tri_state")
		)
		(pad "R1" smd circle
			(at -10.25 2.16 180)
			(size 0.5 0.5)
			(layers "F.Cu" "F.Mask" "F.Paste")
			(net 308 "/OCuLink/~{PE_RST}")
			(pinfunction "~{PE_RST}")
			(pintype "input")
		)
		(pad "R3" smd circle
			(at -9.25 2.16 180)
			(size 0.5 0.5)
			(layers "F.Cu" "F.Mask" "F.Paste")
			(net 231 "unconnected-(U9C-LED3_0-PadR3)")
			(pinfunction "LED3_0")
			(pintype "passive+no_connect")
		)
		(pad "R5" smd circle
			(at -8.25 2.16 180)
			(size 0.5 0.5)
			(layers "F.Cu" "F.Mask" "F.Paste")
			(net 358 "unconnected-(U9C-LED3_1-PadR5)")
			(pinfunction "LED3_1")
			(pintype "passive+no_connect")
		)
		(pad "R7" smd circle
			(at -7.25 2.16 180)
			(size 0.5 0.5)
			(layers "F.Cu" "F.Mask" "F.Paste")
			(net 347 "unconnected-(U9C-SDP1_0-PadR7)")
			(pinfunction "SDP1_0")
			(pintype "passive+no_connect")
		)
		(pad "R9" smd circle
			(at -6.25 2.16 180)
			(size 0.5 0.5)
			(layers "F.Cu" "F.Mask" "F.Paste")
			(net 180 "unconnected-(U9E-RSVDR9_NC-PadR9)")
			(pinfunction "RSVDR9_NC")
			(pintype "passive+no_connect")
		)
		(pad "R11" smd circle
			(at -5.25 2.16 180)
			(size 0.5 0.5)
			(layers "F.Cu" "F.Mask" "F.Paste")
			(net 7 "+3V3")
			(pinfunction "VCC3P3")
			(pintype "passive")
		)
		(pad "R13" smd circle
			(at -4.25 2.16 180)
			(size 0.5 0.5)
			(layers "F.Cu" "F.Mask" "F.Paste")
			(net 9 "VCCD")
			(pinfunction "VCCD")
			(pintype "passive")
		)
		(pad "R15" smd circle
			(at -3.25 2.16 180)
			(size 0.5 0.5)
			(layers "F.Cu" "F.Mask" "F.Paste")
			(net 9 "VCCD")
			(pinfunction "VCCD")
			(pintype "passive")
		)
		(pad "R17" smd circle
			(at -2.25 2.16 180)
			(size 0.5 0.5)
			(layers "F.Cu" "F.Mask" "F.Paste")
			(net 9 "VCCD")
			(pinfunction "VCCD")
			(pintype "passive")
		)
		(pad "R19" smd circle
			(at -1.25 2.16 180)
			(size 0.5 0.5)
			(layers "F.Cu" "F.Mask" "F.Paste")
			(net 9 "VCCD")
			(pinfunction "VCCD")
			(pintype "passive")
		)
		(pad "R21" smd circle
			(at -0.25 2.16 180)
			(size 0.5 0.5)
			(layers "F.Cu" "F.Mask" "F.Paste")
			(net 9 "VCCD")
			(pinfunction "VCCD")
			(pintype "passive")
		)
		(pad "R23" smd circle
			(at 0.75 2.16 180)
			(size 0.5 0.5)
			(layers "F.Cu" "F.Mask" "F.Paste")
			(net 298 "unconnected-(U9E-RSVDR23_NC-PadR23)")
			(pinfunction "RSVDR23_NC")
			(pintype "passive+no_connect")
		)
		(pad "R25" smd circle
			(at 1.75 2.16 180)
			(size 0.5 0.5)
			(layers "F.Cu" "F.Mask" "F.Paste")
			(net 278 "unconnected-(U9E-RSVDR25_NC-PadR25)")
			(pinfunction "RSVDR25_NC")
			(pintype "passive+no_connect")
		)
		(pad "R27" smd circle
			(at 2.75 2.16 180)
			(size 0.5 0.5)
			(layers "F.Cu" "F.Mask" "F.Paste")
			(net 186 "unconnected-(U9E-RSVDR27_NC-PadR27)")
			(pinfunction "RSVDR27_NC")
			(pintype "passive+no_connect")
		)
		(pad "R29" smd circle
			(at 3.75 2.16 180)
			(size 0.5 0.5)
			(layers "F.Cu" "F.Mask" "F.Paste")
			(net 271 "unconnected-(U9G-RSVDR29_NC-PadR29)")
			(pinfunction "RSVDR29_NC")
			(pintype "passive+no_connect")
		)
		(pad "R31" smd circle
			(at 4.75 2.16 180)
			(size 0.5 0.5)
			(layers "F.Cu" "F.Mask" "F.Paste")
			(net 283 "unconnected-(U9G-RSVDR31_NC-PadR31)")
			(pinfunction "RSVDR31_NC")
			(pintype "passive+no_connect")
		)
		(pad "R33" smd circle
			(at 5.75 2.16 180)
			(size 0.5 0.5)
			(layers "F.Cu" "F.Mask" "F.Paste")
			(net 220 "unconnected-(U9F-RSVDR33_NC-PadR33)")
			(pinfunction "RSVDR33_NC")
			(pintype "passive+no_connect")
		)
		(pad "R35" smd circle
			(at 6.75 2.16 180)
			(size 0.5 0.5)
			(layers "F.Cu" "F.Mask" "F.Paste")
			(net 28 "GND")
			(pinfunction "VSS")
			(pintype "passive")
		)
		(pad "R37" smd circle
			(at 7.75 2.16 180)
			(size 0.5 0.5)
			(layers "F.Cu" "F.Mask" "F.Paste")
			(net 187 "unconnected-(U9F-RSVDR37_NC-PadR37)")
			(pinfunction "RSVDR37_NC")
			(pintype "passive+no_connect")
		)
		(pad "R39" smd circle
			(at 8.75 2.16 180)
			(size 0.5 0.5)
			(layers "F.Cu" "F.Mask" "F.Paste")
			(net 394 "/OCuLink/SMBus.SCL")
			(pinfunction "SMBCLK")
			(pintype "open_collector")
		)
		(pad "R41" smd circle
			(at 9.75 2.16 180)
			(size 0.5 0.5)
			(layers "F.Cu" "F.Mask" "F.Paste")
			(net 105 "/Flash memory/FLASH.~{CE}")
			(pinfunction "~{FLSH_CE}")
			(pintype "tri_state")
		)
		(pad "T2" smd circle
			(at -9.75 3.025 180)
			(size 0.5 0.5)
			(layers "F.Cu" "F.Mask" "F.Paste")
			(net 7 "+3V3")
			(pinfunction "VCC3P3_SVR")
			(pintype "power_in")
		)
		(pad "T4" smd circle
			(at -8.75 3.025 180)
			(size 0.5 0.5)
			(layers "F.Cu" "F.Mask" "F.Paste")
			(net 88 "/2xRJ45/~{P1_LED_ACT}")
			(pinfunction "LED2_0")
			(pintype "output")
		)
	)
)
